(kicad_pcb
	(version 20260206)
	(generator "pcbnew")
	(generator_version "10.0")
	(general
		(thickness 1.6)
		(legacy_teardrops no)
	)
	(paper "A4")
	(title_block
		(title "v1-chassis-manager — T6M_CM_d_v01_1031_1645.brd")
		(comment 1 "Open CloudServer (Microsoft) / footprints 2214-2222 of 2512")
	)
	(layers
		(0 "F.Cu" signal "TOP")
		(4 "In1.Cu" signal "GND1")
		(6 "In2.Cu" signal "IN1")
		(8 "In3.Cu" signal "VCC1")
		(10 "In4.Cu" signal "VCC2")
		(12 "In5.Cu" signal "GND2")
		(14 "In6.Cu" signal "IN2")
		(16 "In7.Cu" signal "IN3")
		(18 "In8.Cu" signal "GND3")
		(2 "B.Cu" signal "BOTTOM")
		(9 "F.Adhes" user "F.Adhesive")
		(11 "B.Adhes" user "B.Adhesive")
		(13 "F.Paste" user "Package Geometry/Pastemask Top")
		(15 "B.Paste" user "Package Geometry/Pastemask Bottom")
		(5 "F.SilkS" user "Ref Des/Silkscreen Top")
		(7 "B.SilkS" user "Ref Des/Silkscreen Bottom")
		(1 "F.Mask" user "Board Geometry/Soldermask Top")
		(3 "B.Mask" user "Board Geometry/Soldermask Bottom")
		(17 "Dwgs.User" user "User.Drawings")
		(19 "Cmts.User" user "User.Comments")
		(21 "Eco1.User" user "User.Eco1")
		(23 "Eco2.User" user "User.Eco2")
		(25 "Edge.Cuts" user "Board Geometry/Outline")
		(27 "Margin" user)
		(31 "F.CrtYd" user "Package Geometry/Place Bound Top")
		(29 "B.CrtYd" user "Package Geometry/Place Bound Bottom")
		(35 "F.Fab" user "Ref Des/Assembly Top")
		(33 "B.Fab" user "Ref Des/Assembly Bottom")
	)
	(footprint ""
		(layer "B.Cu")
		(at 28.240736 -117.301772)
		(property "Reference" "C96"
			(at -2.455926 0.028448 0)
			(unlocked yes)
			(layer "B.SilkS")
			(effects
				(font
					(size 0.7874 0.5842)
					(thickness 0.1524)
				)
				(justify left mirror)
			)
		)
		(property "Value" ""
			(at 0 0 0)
			(layer "B.Fab")
			(effects
				(font
					(size 1.27 1.27)
				)
				(justify mirror)
			)
		)
		(duplicate_pad_numbers_are_jumpers no)
		(fp_line
			(start -2.2098 -0.9398)
			(end -2.2098 0.9398)
			(stroke
				(width 0.1524)
				(type default)
			)
			(layer "B.SilkS")
		)
		(fp_line
			(start -2.2098 0.9398)
			(end 2.2098 0.9398)
			(stroke
				(width 0.1524)
				(type default)
			)
			(layer "B.SilkS")
		)
		(fp_line
			(start 0 -0.9398)
			(end 0 0.9398)
			(stroke
				(width 0.1524)
				(type default)
			)
			(layer "B.SilkS")
		)
		(fp_line
			(start 2.2098 -0.9398)
			(end -2.2098 -0.9398)
			(stroke
				(width 0.1524)
				(type default)
			)
			(layer "B.SilkS")
		)
		(fp_line
			(start 2.2098 0.9398)
			(end 2.2098 -0.9398)
			(stroke
				(width 0.1524)
				(type default)
			)
			(layer "B.SilkS")
		)
		(fp_poly
			(pts
				(xy 1.6764 0.889) (xy 1.6764 0.7874) (xy 2.0574 0.7874) (xy 2.0574 -0.7874) (xy 1.6764 -0.7874)
				(xy 1.6764 -0.9398) (xy -1.6764 -0.9398) (xy -1.6764 -0.7874) (xy -2.0574 -0.7874) (xy -2.0574 0.7874)
				(xy -1.6764 0.7874) (xy -1.6764 0.9398) (xy 1.6764 0.9398)
			)
			(stroke
				(width 0)
				(type default)
			)
			(fill no)
			(layer "B.CrtYd")
		)
		(fp_line
			(start -1.700022 -0.899922)
			(end -1.700022 0.899922)
			(stroke
				(width 0.1)
				(type default)
			)
			(layer "B.Fab")
		)
		(fp_line
			(start -1.700022 0.899922)
			(end 1.700022 0.899922)
			(stroke
				(width 0.1)
				(type default)
			)
			(layer "B.Fab")
		)
		(fp_line
			(start 1.700022 -0.899922)
			(end -1.700022 -0.899922)
			(stroke
				(width 0.1)
				(type default)
			)
			(layer "B.Fab")
		)
		(fp_line
			(start 1.700022 0.899922)
			(end 1.700022 -0.899922)
			(stroke
				(width 0.1)
				(type default)
			)
			(layer "B.Fab")
		)
		(pad "1" smd rect
			(at -1.4732 0 180)
			(size 1.1684 1.5748)
			(layers "B.Cu" "B.Mask" "B.Paste")
			(net "P1V05_NODE1")
		)
		(pad "2" smd rect
			(at 1.4732 0 180)
			(size 1.1684 1.5748)
			(layers "B.Cu" "B.Mask" "B.Paste")
			(net "GND")
		)
	)
	(footprint ""
		(layer "B.Cu")
		(at 140.749274 -60.833254)
		(property "Reference" "C352"
			(at -4.939792 0.007874 0)
			(unlocked yes)
			(layer "B.SilkS")
			(effects
				(font
					(size 0.7874 0.5842)
					(thickness 0.1524)
				)
				(justify left mirror)
			)
		)
		(property "Value" ""
			(at 0 0 0)
			(layer "B.Fab")
			(effects
				(font
					(size 1.27 1.27)
				)
				(justify mirror)
			)
		)
		(duplicate_pad_numbers_are_jumpers no)
		(fp_line
			(start -0.7874 -0.4064)
			(end -0.7874 0.4064)
			(stroke
				(width 0.1524)
				(type default)
			)
			(layer "B.SilkS")
		)
		(fp_line
			(start -0.7874 0.4064)
			(end 0.7874 0.4064)
			(stroke
				(width 0.1524)
				(type default)
			)
			(layer "B.SilkS")
		)
		(fp_line
			(start 0 0.381)
			(end 0 -0.381)
			(stroke
				(width 0.1524)
				(type default)
			)
			(layer "B.SilkS")
		)
		(fp_line
			(start 0.7874 -0.4064)
			(end -0.7874 -0.4064)
			(stroke
				(width 0.1524)
				(type default)
			)
			(layer "B.SilkS")
		)
		(fp_line
			(start 0.7874 0.4064)
			(end 0.7874 -0.4064)
			(stroke
				(width 0.1524)
				(type default)
			)
			(layer "B.SilkS")
		)
		(fp_poly
			(pts
				(xy 0.5334 0.254) (xy 0.635 0.254) (xy 0.635 0.2286) (xy 0.635 -0.254) (xy 0.5334 -0.254) (xy 0.5334 -0.2794)
				(xy -0.5334 -0.2794) (xy -0.5334 -0.254) (xy -0.635 -0.254) (xy -0.635 0.254) (xy -0.5334 0.254)
				(xy -0.5334 0.2794) (xy 0.508 0.2794) (xy 0.5334 0.2794)
			)
			(stroke
				(width 0)
				(type default)
			)
			(fill no)
			(layer "B.CrtYd")
		)
		(pad "1" smd rect
			(at -0.40005 0 180)
			(size 0.4572 0.508)
			(layers "B.Cu" "B.Mask" "B.Paste")
			(net "P3V3_NODE1")
		)
		(pad "2" smd rect
			(at 0.40005 0 180)
			(size 0.4572 0.508)
			(layers "B.Cu" "B.Mask" "B.Paste")
			(net "GND")
		)
	)
	(footprint ""
		(layer "B.Cu")
		(at 129.600452 -117.658642)
		(property "Reference" "C10"
			(at 3.208274 0.117856 0)
			(unlocked yes)
			(layer "B.SilkS")
			(effects
				(font
					(size 0.7874 0.5842)
					(thickness 0.1524)
				)
				(justify left mirror)
			)
		)
		(property "Value" ""
			(at 0 0 0)
			(layer "B.Fab")
			(effects
				(font
					(size 1.27 1.27)
				)
				(justify mirror)
			)
		)
		(duplicate_pad_numbers_are_jumpers no)
		(fp_line
			(start -0.7874 -0.4064)
			(end -0.7874 0.4064)
			(stroke
				(width 0.1524)
				(type default)
			)
			(layer "B.SilkS")
		)
		(fp_line
			(start -0.7874 0.4064)
			(end 0.7874 0.4064)
			(stroke
				(width 0.1524)
				(type default)
			)
			(layer "B.SilkS")
		)
		(fp_line
			(start 0 0.381)
			(end 0 -0.381)
			(stroke
				(width 0.1524)
				(type default)
			)
			(layer "B.SilkS")
		)
		(fp_line
			(start 0.7874 -0.4064)
			(end -0.7874 -0.4064)
			(stroke
				(width 0.1524)
				(type default)
			)
			(layer "B.SilkS")
		)
		(fp_line
			(start 0.7874 0.4064)
			(end 0.7874 -0.4064)
			(stroke
				(width 0.1524)
				(type default)
			)
			(layer "B.SilkS")
		)
		(fp_poly
			(pts
				(xy 0.5334 0.254) (xy 0.635 0.254) (xy 0.635 0.2286) (xy 0.635 -0.254) (xy 0.5334 -0.254) (xy 0.5334 -0.2794)
				(xy -0.5334 -0.2794) (xy -0.5334 -0.254) (xy -0.635 -0.254) (xy -0.635 0.254) (xy -0.5334 0.254)
				(xy -0.5334 0.2794) (xy 0.508 0.2794) (xy 0.5334 0.2794)
			)
			(stroke
				(width 0)
				(type default)
			)
			(fill no)
			(layer "B.CrtYd")
		)
		(pad "1" smd rect
			(at -0.40005 0 180)
			(size 0.4572 0.508)
			(layers "B.Cu" "B.Mask" "B.Paste")
			(net "P1V05_CLK_NODE1")
		)
		(pad "2" smd rect
			(at 0.40005 0 180)
			(size 0.4572 0.508)
			(layers "B.Cu" "B.Mask" "B.Paste")
			(net "GND")
		)
	)
	(footprint ""
		(layer "B.Cu")
		(at 75.0062 -30.71114 180)
		(property "Reference" "C153"
			(at -1.788922 -2.09804 0)
			(unlocked yes)
			(layer "B.SilkS")
			(effects
				(font
					(size 0.7874 0.5842)
					(thickness 0.1524)
				)
				(justify left mirror)
			)
		)
		(property "Value" ""
			(at 0 0 0)
			(layer "B.Fab")
			(effects
				(font
					(size 1.27 1.27)
				)
				(justify mirror)
			)
		)
		(duplicate_pad_numbers_are_jumpers no)
		(fp_line
			(start 0.7874 0.4064)
			(end 0.7874 -0.4064)
			(stroke
				(width 0.1524)
				(type default)
			)
			(layer "B.SilkS")
		)
		(fp_line
			(start 0.7874 -0.4064)
			(end -0.7874 -0.4064)
			(stroke
				(width 0.1524)
				(type default)
			)
			(layer "B.SilkS")
		)
		(fp_line
			(start 0 0.381)
			(end 0 -0.381)
			(stroke
				(width 0.1524)
				(type default)
			)
			(layer "B.SilkS")
		)
		(fp_line
			(start -0.7874 0.4064)
			(end 0.7874 0.4064)
			(stroke
				(width 0.1524)
				(type default)
			)
			(layer "B.SilkS")
		)
		(fp_line
			(start -0.7874 -0.4064)
			(end -0.7874 0.4064)
			(stroke
				(width 0.1524)
				(type default)
			)
			(layer "B.SilkS")
		)
		(fp_poly
			(pts
				(xy 0.5334 0.254) (xy 0.635 0.254) (xy 0.635 0.2286) (xy 0.635 -0.254) (xy 0.5334 -0.254) (xy 0.5334 -0.2794)
				(xy -0.5334 -0.2794) (xy -0.5334 -0.254) (xy -0.635 -0.254) (xy -0.635 0.254) (xy -0.5334 0.254)
				(xy -0.5334 0.2794) (xy 0.508 0.2794) (xy 0.5334 0.2794)
			)
			(stroke
				(width 0)
				(type default)
			)
			(fill no)
			(layer "B.CrtYd")
		)
		(pad "1" smd rect
			(at -0.40005 0)
			(size 0.4572 0.508)
			(layers "B.Cu" "B.Mask" "B.Paste")
			(net "PV_VDDR_NODE1")
		)
		(pad "2" smd rect
			(at 0.40005 0)
			(size 0.4572 0.508)
			(layers "B.Cu" "B.Mask" "B.Paste")
			(net "GND")
		)
	)
	(footprint ""
		(layer "B.Cu")
		(at 131.464558 -113.912904 90)
		(property "Reference" "C2"
			(at 1.36398 0.478028 270)
			(unlocked yes)
			(layer "B.SilkS")
			(effects
				(font
					(size 0.7874 0.5842)
					(thickness 0.1524)
				)
				(justify left mirror)
			)
		)
		(property "Value" ""
			(at 0 0 90)
			(layer "B.Fab")
			(effects
				(font
					(size 1.27 1.27)
				)
				(justify mirror)
			)
		)
		(duplicate_pad_numbers_are_jumpers no)
		(fp_line
			(start 0.7874 -0.4064)
			(end -0.7874 -0.4064)
			(stroke
				(width 0.1524)
				(type default)
			)
			(layer "B.SilkS")
		)
		(fp_line
			(start -0.7874 -0.4064)
			(end -0.7874 0.4064)
			(stroke
				(width 0.1524)
				(type default)
			)
			(layer "B.SilkS")
		)
		(fp_line
			(start 0 0.381)
			(end 0 -0.381)
			(stroke
				(width 0.1524)
				(type default)
			)
			(layer "B.SilkS")
		)
		(fp_line
			(start 0.7874 0.4064)
			(end 0.7874 -0.4064)
			(stroke
				(width 0.1524)
				(type default)
			)
			(layer "B.SilkS")
		)
		(fp_line
			(start -0.7874 0.4064)
			(end 0.7874 0.4064)
			(stroke
				(width 0.1524)
				(type default)
			)
			(layer "B.SilkS")
		)
		(fp_poly
			(pts
				(xy 0.5334 0.254) (xy 0.635 0.254) (xy 0.635 0.2286) (xy 0.635 -0.254) (xy 0.5334 -0.254) (xy 0.5334 -0.2794)
				(xy -0.5334 -0.2794) (xy -0.5334 -0.254) (xy -0.635 -0.254) (xy -0.635 0.254) (xy -0.5334 0.254)
				(xy -0.5334 0.2794) (xy 0.508 0.2794) (xy 0.5334 0.2794)
			)
			(stroke
				(width 0)
				(type default)
			)
			(fill no)
			(layer "B.CrtYd")
		)
		(pad "1" smd rect
			(at -0.40005 0 270)
			(size 0.4572 0.508)
			(layers "B.Cu" "B.Mask" "B.Paste")
			(net "P3V3_CLK_NODE1")
		)
		(pad "2" smd rect
			(at 0.40005 0 270)
			(size 0.4572 0.508)
			(layers "B.Cu" "B.Mask" "B.Paste")
			(net "GND")
		)
	)
	(footprint ""
		(layer "B.Cu")
		(at 62.724538 -71.022718 -90)
		(property "Reference" "C124"
			(at 33.088326 14.768068 270)
			(unlocked yes)
			(layer "B.SilkS")
			(effects
				(font
					(size 0.7874 0.5842)
					(thickness 0.1524)
				)
				(justify left mirror)
			)
		)
		(property "Value" ""
			(at 0 0 90)
			(layer "B.Fab")
			(effects
				(font
					(size 1.27 1.27)
				)
				(justify mirror)
			)
		)
		(duplicate_pad_numbers_are_jumpers no)
		(fp_line
			(start -0.7874 0.4064)
			(end 0.7874 0.4064)
			(stroke
				(width 0.1524)
				(type default)
			)
			(layer "B.SilkS")
		)
		(fp_line
			(start 0.7874 0.4064)
			(end 0.7874 -0.4064)
			(stroke
				(width 0.1524)
				(type default)
			)
			(layer "B.SilkS")
		)
		(fp_line
			(start 0 0.381)
			(end 0 -0.381)
			(stroke
				(width 0.1524)
				(type default)
			)
			(layer "B.SilkS")
		)
		(fp_line
			(start -0.7874 -0.4064)
			(end -0.7874 0.4064)
			(stroke
				(width 0.1524)
				(type default)
			)
			(layer "B.SilkS")
		)
		(fp_line
			(start 0.7874 -0.4064)
			(end -0.7874 -0.4064)
			(stroke
				(width 0.1524)
				(type default)
			)
			(layer "B.SilkS")
		)
		(fp_poly
			(pts
				(xy 0.5334 0.254) (xy 0.635 0.254) (xy 0.635 0.2286) (xy 0.635 -0.254) (xy 0.5334 -0.254) (xy 0.5334 -0.2794)
				(xy -0.5334 -0.2794) (xy -0.5334 -0.254) (xy -0.635 -0.254) (xy -0.635 0.254) (xy -0.5334 0.254)
				(xy -0.5334 0.2794) (xy 0.508 0.2794) (xy 0.5334 0.2794)
			)
			(stroke
				(width 0)
				(type default)
			)
			(fill no)
			(layer "B.CrtYd")
		)
		(pad "1" smd rect
			(at -0.40005 0 90)
			(size 0.4572 0.508)
			(layers "B.Cu" "B.Mask" "B.Paste")
			(net "P1V05_NODE1")
		)
		(pad "2" smd rect
			(at 0.40005 0 90)
			(size 0.4572 0.508)
			(layers "B.Cu" "B.Mask" "B.Paste")
			(net "GND")
		)
	)
	(footprint ""
		(layer "B.Cu")
		(at 61.037978 -79.74965 90)
		(property "Reference" "C100"
			(at -32.526478 -14.402308 270)
			(unlocked yes)
			(layer "B.SilkS")
			(effects
				(font
					(size 0.7874 0.5842)
					(thickness 0.1524)
				)
				(justify left mirror)
			)
		)
		(property "Value" ""
			(at 0 0 90)
			(layer "B.Fab")
			(effects
				(font
					(size 1.27 1.27)
				)
				(justify mirror)
			)
		)
		(duplicate_pad_numbers_are_jumpers no)
		(fp_line
			(start 0.7874 -0.4064)
			(end -0.7874 -0.4064)
			(stroke
				(width 0.1524)
				(type default)
			)
			(layer "B.SilkS")
		)
		(fp_line
			(start -0.7874 -0.4064)
			(end -0.7874 0.4064)
			(stroke
				(width 0.1524)
				(type default)
			)
			(layer "B.SilkS")
		)
		(fp_line
			(start 0 0.381)
			(end 0 -0.381)
			(stroke
				(width 0.1524)
				(type default)
			)
			(layer "B.SilkS")
		)
		(fp_line
			(start 0.7874 0.4064)
			(end 0.7874 -0.4064)
			(stroke
				(width 0.1524)
				(type default)
			)
			(layer "B.SilkS")
		)
		(fp_line
			(start -0.7874 0.4064)
			(end 0.7874 0.4064)
			(stroke
				(width 0.1524)
				(type default)
			)
			(layer "B.SilkS")
		)
		(fp_poly
			(pts
				(xy 0.5334 0.254) (xy 0.635 0.254) (xy 0.635 0.2286) (xy 0.635 -0.254) (xy 0.5334 -0.254) (xy 0.5334 -0.2794)
				(xy -0.5334 -0.2794) (xy -0.5334 -0.254) (xy -0.635 -0.254) (xy -0.635 0.254) (xy -0.5334 0.254)
				(xy -0.5334 0.2794) (xy 0.508 0.2794) (xy 0.5334 0.2794)
			)
			(stroke
				(width 0)
				(type default)
			)
			(fill no)
			(layer "B.CrtYd")
		)
		(pad "1" smd rect
			(at -0.40005 0 270)
			(size 0.4572 0.508)
			(layers "B.Cu" "B.Mask" "B.Paste")
			(net "P1V05_NODE1")
		)
		(pad "2" smd rect
			(at 0.40005 0 270)
			(size 0.4572 0.508)
			(layers "B.Cu" "B.Mask" "B.Paste")
			(net "GND")
		)
	)
	(footprint ""
		(layer "B.Cu")
		(at 167.63238 -151.496522)
		(property "Reference" "C451"
			(at 4.681728 0.02159 0)
			(unlocked yes)
			(layer "B.SilkS")
			(effects
				(font
					(size 0.7874 0.5842)
					(thickness 0.1524)
				)
				(justify left mirror)
			)
		)
		(property "Value" ""
			(at 0 0 0)
			(layer "B.Fab")
			(effects
				(font
					(size 1.27 1.27)
				)
				(justify mirror)
			)
		)
		(duplicate_pad_numbers_are_jumpers no)
		(fp_line
			(start -0.7874 -0.4064)
			(end -0.7874 0.4064)
			(stroke
				(width 0.1524)
				(type default)
			)
			(layer "B.SilkS")
		)
		(fp_line
			(start -0.7874 0.4064)
			(end 0.7874 0.4064)
			(stroke
				(width 0.1524)
				(type default)
			)
			(layer "B.SilkS")
		)
		(fp_line
			(start 0 0.381)
			(end 0 -0.381)
			(stroke
				(width 0.1524)
				(type default)
			)
			(layer "B.SilkS")
		)
		(fp_line
			(start 0.7874 -0.4064)
			(end -0.7874 -0.4064)
			(stroke
				(width 0.1524)
				(type default)
			)
			(layer "B.SilkS")
		)
		(fp_line
			(start 0.7874 0.4064)
			(end 0.7874 -0.4064)
			(stroke
				(width 0.1524)
				(type default)
			)
			(layer "B.SilkS")
		)
		(fp_poly
			(pts
				(xy 0.5334 0.254) (xy 0.635 0.254) (xy 0.635 0.2286) (xy 0.635 -0.254) (xy 0.5334 -0.254) (xy 0.5334 -0.2794)
				(xy -0.5334 -0.2794) (xy -0.5334 -0.254) (xy -0.635 -0.254) (xy -0.635 0.254) (xy -0.5334 0.254)
				(xy -0.5334 0.2794) (xy 0.508 0.2794) (xy 0.5334 0.2794)
			)
			(stroke
				(width 0)
				(type default)
			)
			(fill no)
			(layer "B.CrtYd")
		)
		(pad "1" smd rect
			(at -0.40005 0 180)
			(size 0.4572 0.508)
			(layers "B.Cu" "B.Mask" "B.Paste")
			(net "P1V9_LAN2")
		)
		(pad "2" smd rect
			(at 0.40005 0 180)
			(size 0.4572 0.508)
			(layers "B.Cu" "B.Mask" "B.Paste")
			(net "GND")
		)
	)
	(footprint ""
		(layer "B.Cu")
		(at 78.241906 -83.923124)
		(property "Reference" "R1216"
			(at -12.435586 31.674816 0)
			(unlocked yes)
			(layer "B.SilkS")
			(effects
				(font
					(size 0.7874 0.5842)
					(thickness 0.1524)
				)
				(justify left mirror)
			)
		)
		(property "Value" ""
			(at 0 0 0)
			(layer "B.Fab")
			(effects
				(font
					(size 1.27 1.27)
				)
				(justify mirror)
			)
		)
		(duplicate_pad_numbers_are_jumpers no)
		(fp_line
			(start -0.7874 -0.4064)
			(end -0.7874 0.4064)
			(stroke
				(width 0.1524)
				(type default)
			)
			(layer "B.SilkS")
		)
		(fp_line
			(start -0.7874 0.4064)
			(end 0.7874 0.4064)
			(stroke
				(width 0.1524)
				(type default)
			)
			(layer "B.SilkS")
		)
		(fp_line
			(start 0.7874 -0.4064)
			(end -0.7874 -0.4064)
			(stroke
				(width 0.1524)
				(type default)
			)
			(layer "B.SilkS")
		)
		(fp_line
			(start 0.7874 0.4064)
			(end 0.7874 -0.4064)
			(stroke
				(width 0.1524)
				(type default)
			)
			(layer "B.SilkS")
		)
		(fp_poly
			(pts
				(xy 0.508 0.2794) (xy 0.508 0.2286) (xy 0.635 0.2286) (xy 0.635 -0.254) (xy 0.5334 -0.254) (xy 0.5334 -0.2794)
				(xy -0.5334 -0.2794) (xy -0.5334 -0.254) (xy -0.635 -0.254) (xy -0.635 0.254) (xy -0.5334 0.254)
				(xy -0.5334 0.2794)
			)
			(stroke
				(width 0)
				(type default)
			)
			(fill no)
			(layer "B.CrtYd")
		)
		(pad "1" smd rect
			(at -0.40005 0 180)
			(size 0.4572 0.508)
			(layers "B.Cu" "B.Mask" "B.Paste")
			(net "CPU_NODE1_PROCHOT_N")
		)
		(pad "2" smd rect
			(at 0.40005 0 180)
			(size 0.4572 0.508)
			(layers "B.Cu" "B.Mask" "B.Paste")
			(net "P3V3_NODE1")
		)
	)
)
